# BASEBOARD_FAB2 (Tioga Pass) — schematic netlist excerpt (pin names and nets, part order shuffled) for the footprints in the layout excerpt that follows; sources: Cadence DE-HDL packaged netlist, KiCad conversion of Wiwynn_Tioga_Pass_MB.brd

R25W175  RES  1.00K 1% CHIP  pkg 0402  page 255 : A = PD_GTL2014_6_B0 ; B = GND
C8P24  CAP  47UF 4V 20% X6S  pkg 0805  page 76 : A = PVCCIN_CPU1 ; B = GND
R2U35  RES  20.0 1% EMPTY  pkg 0402  page 108 : A = SMB_SLOTX24_PCH_STBY_LVC3_SDA ; B = SMB_SLOTX24_STBY_LVC3_SDA_R2

(kicad_pcb
	(version 20260206)
	(generator "pcbnew")
	(generator_version "10.0")
	(general
		(thickness 1.6)
		(legacy_teardrops no)
	)
	(paper "A4")
	(title_block
		(title "Wiwynn_Tioga_Pass_MB.brd")
		(comment 1 "Tioga Pass / footprints 2479-2481 of 4770")
	)
	(layers
		(0 "F.Cu" signal "TOP")
		(4 "In1.Cu" signal "L2GND")
		(6 "In2.Cu" signal "L3")
		(8 "In3.Cu" signal "L4GND")
		(10 "In4.Cu" signal "L5")
		(12 "In5.Cu" signal "L6GND")
		(14 "In6.Cu" signal "L7VCC")
		(16 "In7.Cu" signal "L8VCC")
		(18 "In8.Cu" signal "L9GND")
		(20 "In9.Cu" signal "L10")
		(22 "In10.Cu" signal "L11GND")
		(24 "In11.Cu" signal "L12")
		(26 "In12.Cu" signal "L13GND")
		(2 "B.Cu" signal "BOTTOM")
		(9 "F.Adhes" user "F.Adhesive")
		(11 "B.Adhes" user "B.Adhesive")
		(13 "F.Paste" user "Package Geometry/Pastemask Top")
		(15 "B.Paste" user "Package Geometry/Pastemask Bottom")
		(5 "F.SilkS" user "Ref Des/Silkscreen Top")
		(7 "B.SilkS" user "Ref Des/Silkscreen Bottom")
		(1 "F.Mask" user "Board Geometry/Soldermask Top")
		(3 "B.Mask" user "Board Geometry/Soldermask Bottom")
		(17 "Dwgs.User" user "User.Drawings")
		(19 "Cmts.User" user "User.Comments")
		(21 "Eco1.User" user "User.Eco1")
		(23 "Eco2.User" user "User.Eco2")
		(25 "Edge.Cuts" user "Board Geometry/Outline")
		(27 "Margin" user)
		(31 "F.CrtYd" user "Package Geometry/Place Bound Top")
		(29 "B.CrtYd" user "Package Geometry/Place Bound Bottom")
		(35 "F.Fab" user "Ref Des/Assembly Top")
		(33 "B.Fab" user "Ref Des/Assembly Bottom")
	)
	(footprint ""
		(layer "B.Cu")
		(at 469.197944 -9.64692 180)
		(property "Reference" "R2U35"
			(at 0.8382 -0.67818 180)
			(unlocked yes)
			(layer "B.SilkS")
			(effects
				(font
					(size 0.4064 0.254)
					(thickness 0.1524)
				)
				(justify left mirror)
			)
		)
		(property "Value" ""
			(at 0 0 0)
			(layer "B.Fab")
			(effects
				(font
					(size 1.27 1.27)
				)
				(justify mirror)
			)
		)
		(duplicate_pad_numbers_are_jumpers no)
		(fp_poly
			(pts
				(xy 0.2794 -0.1016) (xy -0.2794 -0.1016) (xy -0.2794 0.9906) (xy 0.2794 0.9906)
			)
			(stroke
				(width 0)
				(type default)
			)
			(fill no)
			(layer "B.CrtYd")
		)
		(fp_line
			(start 0.2794 0.9906)
			(end -0.2794 0.9906)
			(stroke
				(width 0.1)
				(type default)
			)
			(layer "B.Fab")
		)
		(fp_line
			(start 0.2794 -0.1016)
			(end 0.2794 0.9906)
			(stroke
				(width 0.1)
				(type default)
			)
			(layer "B.Fab")
		)
		(fp_line
			(start -0.2794 0.9906)
			(end -0.2794 -0.1016)
			(stroke
				(width 0.1)
				(type default)
			)
			(layer "B.Fab")
		)
		(fp_line
			(start -0.2794 -0.1016)
			(end 0.2794 -0.1016)
			(stroke
				(width 0.1)
				(type default)
			)
			(layer "B.Fab")
		)
		(pad "1" smd rect
			(at 0 0)
			(size 0.508 0.508)
			(layers "B.Cu" "B.Mask" "B.Paste")
			(net "SMB_SLOTX24_PCH_STBY_LVC3_SDA")
		)
		(pad "2" smd rect
			(at 0 0.889)
			(size 0.508 0.508)
			(layers "B.Cu" "B.Mask" "B.Paste")
			(net "SMB_SLOTX24_STBY_LVC3_SDA_R2")
		)
		(zone
			(layer "B.Cu")
			(hatch none 0.5)
			(connect_pads
				(clearance 0)
			)
			(min_thickness 0.25)
			(keepout
				(tracks not_allowed)
				(vias allowed)
				(pads allowed)
				(copperpour not_allowed)
				(footprints allowed)
			)
			(placement
				(enabled no)
				(sheetname "")
			)
			(fill
				(thermal_gap 0.5)
				(thermal_bridge_width 0.5)
				(island_removal_mode 0)
			)
			(polygon
				(pts
					(xy 468.943944 -10.28192) (xy 469.451944 -10.28192) (xy 469.451944 -9.90092) (xy 468.943944 -9.90092)
				)
			)
		)
		(zone
			(layer "B.Cu")
			(hatch none 0.5)
			(connect_pads
				(clearance 0)
			)
			(min_thickness 0.25)
			(keepout
				(tracks allowed)
				(vias not_allowed)
				(pads allowed)
				(copperpour not_allowed)
				(footprints allowed)
			)
			(placement
				(enabled no)
				(sheetname "")
			)
			(fill
				(thermal_gap 0.5)
				(thermal_bridge_width 0.5)
				(island_removal_mode 0)
			)
			(polygon
				(pts
					(xy 468.943944 -9.90092) (xy 469.451944 -9.90092) (xy 469.451944 -10.28192) (xy 468.943944 -10.28192)
				)
			)
		)
	)
	(footprint ""
		(layer "B.Cu")
		(at 102.692454 -73.51014)
		(property "Reference" "C8P24"
			(at 0 0 0)
			(layer "B.SilkS")
			(hide yes)
			(effects
				(font
					(size 1.27 1.27)
				)
				(justify mirror)
			)
		)
		(property "Value" ""
			(at 0 0 0)
			(layer "B.Fab")
			(effects
				(font
					(size 1.27 1.27)
				)
				(justify mirror)
			)
		)
		(duplicate_pad_numbers_are_jumpers no)
		(fp_poly
			(pts
				(xy 0.7239 -0.2159) (xy -0.7239 -0.2159) (xy -0.7239 1.9939) (xy 0.7239 1.9939)
			)
			(stroke
				(width 0)
				(type default)
			)
			(fill no)
			(layer "B.CrtYd")
		)
		(fp_line
			(start -0.7239 -0.2159)
			(end 0.7239 -0.2159)
			(stroke
				(width 0.1)
				(type default)
			)
			(layer "B.Fab")
		)
		(fp_line
			(start -0.7239 1.9939)
			(end -0.7239 -0.2159)
			(stroke
				(width 0.1)
				(type default)
			)
			(layer "B.Fab")
		)
		(fp_line
			(start 0.7239 -0.2159)
			(end 0.7239 1.9939)
			(stroke
				(width 0.1)
				(type default)
			)
			(layer "B.Fab")
		)
		(fp_line
			(start 0.7239 1.9939)
			(end -0.7239 1.9939)
			(stroke
				(width 0.1)
				(type default)
			)
			(layer "B.Fab")
		)
		(pad "1" smd rect
			(at 0 0 180)
			(size 1.27 1.016)
			(layers "B.Cu" "B.Mask" "B.Paste")
			(net "PVCCIN_CPU1")
		)
		(pad "2" smd rect
			(at 0 1.778 180)
			(size 1.27 1.016)
			(layers "B.Cu" "B.Mask" "B.Paste")
			(net "GND")
		)
		(zone
			(layer "B.Cu")
			(hatch none 0.5)
			(connect_pads
				(clearance 0)
			)
			(min_thickness 0.25)
			(keepout
				(tracks not_allowed)
				(vias allowed)
				(pads allowed)
				(copperpour not_allowed)
				(footprints allowed)
			)
			(placement
				(enabled no)
				(sheetname "")
			)
			(fill
				(thermal_gap 0.5)
				(thermal_bridge_width 0.5)
				(island_removal_mode 0)
			)
			(polygon
				(pts
					(xy 103.327454 -73.00214) (xy 102.057454 -73.00214) (xy 102.057454 -72.24014) (xy 103.327454 -72.24014)
				)
			)
		)
	)
	(footprint ""
		(layer "B.Cu")
		(at 450.215 -147.8026 -90)
		(property "Reference" "R25W175"
			(at 0.8382 -0.67818 270)
			(unlocked yes)
			(layer "B.SilkS")
			(effects
				(font
					(size 0.4064 0.254)
					(thickness 0.1524)
				)
				(justify left mirror)
			)
		)
		(property "Value" ""
			(at 0 0 90)
			(layer "B.Fab")
			(effects
				(font
					(size 1.27 1.27)
				)
				(justify mirror)
			)
		)
		(duplicate_pad_numbers_are_jumpers no)
		(fp_poly
			(pts
				(xy 0.2794 -0.1016) (xy -0.2794 -0.1016) (xy -0.2794 0.9906) (xy 0.2794 0.9906)
			)
			(stroke
				(width 0)
				(type default)
			)
			(fill no)
			(layer "B.CrtYd")
		)
		(fp_line
			(start -0.2794 0.9906)
			(end -0.2794 -0.1016)
			(stroke
				(width 0.1)
				(type default)
			)
			(layer "B.Fab")
		)
		(fp_line
			(start 0.2794 0.9906)
			(end -0.2794 0.9906)
			(stroke
				(width 0.1)
				(type default)
			)
			(layer "B.Fab")
		)
		(fp_line
			(start -0.2794 -0.1016)
			(end 0.2794 -0.1016)
			(stroke
				(width 0.1)
				(type default)
			)
			(layer "B.Fab")
		)
		(fp_line
			(start 0.2794 -0.1016)
			(end 0.2794 0.9906)
			(stroke
				(width 0.1)
				(type default)
			)
			(layer "B.Fab")
		)
		(pad "1" smd rect
			(at 0 0 90)
			(size 0.508 0.508)
			(layers "B.Cu" "B.Mask" "B.Paste")
			(net "PD_GTL2014_6_B0")
		)
		(pad "2" smd rect
			(at 0 0.889 90)
			(size 0.508 0.508)
			(layers "B.Cu" "B.Mask" "B.Paste")
			(net "GND")
		)
		(zone
			(layer "B.Cu")
			(hatch none 0.5)
			(connect_pads
				(clearance 0)
			)
			(min_thickness 0.25)
			(keepout
				(tracks not_allowed)
				(vias allowed)
				(pads allowed)
				(copperpour not_allowed)
				(footprints allowed)
			)
			(placement
				(enabled no)
				(sheetname "")
			)
			(fill
				(thermal_gap 0.5)
				(thermal_bridge_width 0.5)
				(island_removal_mode 0)
			)
			(polygon
				(pts
					(xy 449.58 -147.5486) (xy 449.58 -148.0566) (xy 449.961 -148.0566) (xy 449.961 -147.5486)
				)
			)
		)
		(zone
			(layer "B.Cu")
			(hatch none 0.5)
			(connect_pads
				(clearance 0)
			)
			(min_thickness 0.25)
			(keepout
				(tracks allowed)
				(vias not_allowed)
				(pads allowed)
				(copperpour not_allowed)
				(footprints allowed)
			)
			(placement
				(enabled no)
				(sheetname "")
			)
			(fill
				(thermal_gap 0.5)
				(thermal_bridge_width 0.5)
				(island_removal_mode 0)
			)
			(polygon
				(pts
					(xy 449.961 -147.5486) (xy 449.961 -148.0566) (xy 449.58 -148.0566) (xy 449.58 -147.5486)
				)
			)
		)
	)
)
